# TIMECARD (Time Appliance Project (Time Card)) — schematic netlist excerpt (pin names and nets, part order shuffled) for the footprints in the layout excerpt that follows; sources: Cadence DE-HDL packaged netlist, KiCad conversion of R4006-B0001-02_R01.brd

R342  RESISTOR  4.7KOHM 1%  pkg SMC_0402R_H016  page 20 : \1\ = XP3R3V_FPGA ; \2\ = BNO080_EVN_SCL
C101  CAPACITOR  0.1UF 25V 10%  pkg SMC_0402R_H022  page 24 : \1\ = XP3R3V_VPHY ; \2\ = SG

(kicad_pcb
	(version 20260206)
	(generator "pcbnew")
	(generator_version "10.0")
	(general
		(thickness 1.6)
		(legacy_teardrops no)
	)
	(paper "A4")
	(title_block
		(title "timecard-production-celestica-r4006 — R4006-B0001-02_R01.brd")
		(comment 1 "Time Appliance Project (Time Card) / footprints 917-918 of 1113")
	)
	(layers
		(0 "F.Cu" signal "TOP")
		(4 "In1.Cu" signal "L02_GND1")
		(6 "In2.Cu" signal "L03_SIG1")
		(8 "In3.Cu" signal "L04_GND2")
		(10 "In4.Cu" signal "L05_VCC1")
		(12 "In5.Cu" signal "L06_VCC2")
		(14 "In6.Cu" signal "L07_GND3")
		(16 "In7.Cu" signal "L08_SIG2")
		(18 "In8.Cu" signal "L09_GND4")
		(2 "B.Cu" signal "BOTTOM")
		(9 "F.Adhes" user "F.Adhesive")
		(11 "B.Adhes" user "B.Adhesive")
		(13 "F.Paste" user "Package Geometry/Pastemask Top")
		(15 "B.Paste" user "Package Geometry/Pastemask Bottom")
		(5 "F.SilkS" user "Ref Des/Silkscreen Top")
		(7 "B.SilkS" user "Ref Des/Silkscreen Bottom")
		(1 "F.Mask" user "Board Geometry/Soldermask Top")
		(3 "B.Mask" user "Board Geometry/Soldermask Bottom")
		(17 "Dwgs.User" user "User.Drawings")
		(19 "Cmts.User" user "User.Comments")
		(21 "Eco1.User" user "User.Eco1")
		(23 "Eco2.User" user "User.Eco2")
		(25 "Edge.Cuts" user "Board Geometry/Outline")
		(27 "Margin" user)
		(31 "F.CrtYd" user "Package Geometry/Place Bound Top")
		(29 "B.CrtYd" user "Package Geometry/Place Bound Bottom")
		(35 "F.Fab" user "Ref Des/Assembly Top")
		(33 "B.Fab" user "Ref Des/Assembly Bottom")
	)
	(footprint ""
		(layer "B.Cu")
		(at 86.233 -73.279 -90)
		(property "Reference" "R342"
			(at 3.556 0.16637 270)
			(unlocked yes)
			(layer "B.SilkS")
			(effects
				(font
					(size 0.7874 0.5842)
					(thickness 0.1524)
				)
				(justify mirror)
			)
		)
		(property "Value" "VAL*"
			(at -0.02032 2.13233 270)
			(unlocked yes)
			(layer "B.Fab")
			(hide yes)
			(effects
				(font
					(size 0.7874 0.5842)
					(thickness 0.1524)
				)
				(justify mirror)
			)
		)
		(property "Tolerance" "TOL*"
			(at -0.044704 3.05435 270)
			(unlocked yes)
			(layer "Cmts.User")
			(hide yes)
			(effects
				(font
					(size 0.7874 0.5842)
					(thickness 0.1524)
				)
				(justify mirror)
			)
		)
		(property "User Part Number" "PARTNUM*"
			(at -0.02032 4.024884 270)
			(unlocked yes)
			(layer "Cmts.User")
			(hide yes)
			(effects
				(font
					(size 0.7874 0.5842)
					(thickness 0.1524)
				)
				(justify mirror)
			)
		)
		(property "Device Type" "RESISTOR-G155-14701-01,4.7KOHMA"
			(at -0.008382 1.210564 270)
			(unlocked yes)
			(layer "B.Fab")
			(hide yes)
			(effects
				(font
					(size 0.7874 0.5842)
					(thickness 0.1524)
				)
				(justify mirror)
			)
		)
		(duplicate_pad_numbers_are_jumpers no)
		(fp_line
			(start -1.143 0.5588)
			(end -1.143 -0.5588)
			(stroke
				(width 0.1)
				(type default)
			)
			(layer "B.SilkS")
		)
		(fp_line
			(start 1.143 0.5588)
			(end -1.143 0.5588)
			(stroke
				(width 0.1)
				(type default)
			)
			(layer "B.SilkS")
		)
		(fp_line
			(start -1.143 -0.5588)
			(end 1.143 -0.5588)
			(stroke
				(width 0.1)
				(type default)
			)
			(layer "B.SilkS")
		)
		(fp_line
			(start 1.143 -0.5588)
			(end 1.143 0.5588)
			(stroke
				(width 0.1)
				(type default)
			)
			(layer "B.SilkS")
		)
		(fp_rect
			(start -1.143 0.5588)
			(end 1.143 -0.5588)
			(stroke
				(width 0)
				(type default)
			)
			(fill no)
			(layer "B.CrtYd")
		)
		(fp_line
			(start -0.508 0.3048)
			(end -0.508 -0.3048)
			(stroke
				(width 0.1)
				(type default)
			)
			(layer "B.Fab")
		)
		(fp_line
			(start 0.508 0.3048)
			(end -0.508 0.3048)
			(stroke
				(width 0.1)
				(type default)
			)
			(layer "B.Fab")
		)
		(fp_line
			(start -0.508 -0.3048)
			(end 0.508 -0.3048)
			(stroke
				(width 0.1)
				(type default)
			)
			(layer "B.Fab")
		)
		(fp_line
			(start 0.508 -0.3048)
			(end 0.508 0.3048)
			(stroke
				(width 0.1)
				(type default)
			)
			(layer "B.Fab")
		)
		(pad "1" smd rect
			(at 0.5334 0 90)
			(size 0.7112 0.6096)
			(layers "B.Cu" "B.Mask" "B.Paste")
			(net "XP3R3V_FPGA")
		)
		(pad "2" smd rect
			(at -0.5334 0 90)
			(size 0.7112 0.6096)
			(layers "B.Cu" "B.Mask" "B.Paste")
			(net "BNO080_EVN_SCL")
		)
		(zone
			(layer "B.Cu")
			(hatch none 0.5)
			(connect_pads
				(clearance 0)
			)
			(min_thickness 0.25)
			(keepout
				(tracks allowed)
				(vias not_allowed)
				(pads allowed)
				(copperpour not_allowed)
				(footprints allowed)
			)
			(placement
				(enabled no)
				(sheetname "")
			)
			(fill
				(thermal_gap 0.5)
				(thermal_bridge_width 0.5)
				(island_removal_mode 0)
			)
			(polygon
				(pts
					(xy 85.9282 -73.3552) (xy 85.9282 -73.2028) (xy 86.5378 -73.2028) (xy 86.5378 -73.3552)
				)
			)
		)
	)
	(footprint ""
		(layer "B.Cu")
		(at 32.131 -91.059 -90)
		(property "Reference" "C101"
			(at -3.175 -0.08763 270)
			(unlocked yes)
			(layer "B.SilkS")
			(effects
				(font
					(size 0.7874 0.5842)
					(thickness 0.1524)
				)
				(justify mirror)
			)
		)
		(property "Value" "VAL*"
			(at -0.0762 2.067306 270)
			(unlocked yes)
			(layer "B.Fab")
			(hide yes)
			(effects
				(font
					(size 0.7874 0.5842)
					(thickness 0.1524)
				)
				(justify mirror)
			)
		)
		(property "Tolerance" "TOL*"
			(at -0.0762 3.032506 270)
			(unlocked yes)
			(layer "Cmts.User")
			(hide yes)
			(effects
				(font
					(size 0.7874 0.5842)
					(thickness 0.1524)
				)
				(justify mirror)
			)
		)
		(property "User Part Number" "PARTNUM*"
			(at -0.1016 4.023106 270)
			(unlocked yes)
			(layer "Cmts.User")
			(hide yes)
			(effects
				(font
					(size 0.7874 0.5842)
					(thickness 0.1524)
				)
				(justify mirror)
			)
		)
		(property "Device Type" "CAPACITOR-G105-0B104-EK,0.1UF,A"
			(at -0.0508 1.127506 270)
			(unlocked yes)
			(layer "B.Fab")
			(hide yes)
			(effects
				(font
					(size 0.7874 0.5842)
					(thickness 0.1524)
				)
				(justify mirror)
			)
		)
		(duplicate_pad_numbers_are_jumpers no)
		(fp_line
			(start -1.143 0.5588)
			(end -1.143 -0.5588)
			(stroke
				(width 0.1)
				(type default)
			)
			(layer "B.SilkS")
		)
		(fp_line
			(start 1.143 0.5588)
			(end -1.143 0.5588)
			(stroke
				(width 0.1)
				(type default)
			)
			(layer "B.SilkS")
		)
		(fp_line
			(start -1.143 -0.5588)
			(end 1.143 -0.5588)
			(stroke
				(width 0.1)
				(type default)
			)
			(layer "B.SilkS")
		)
		(fp_line
			(start 1.143 -0.5588)
			(end 1.143 0.5588)
			(stroke
				(width 0.1)
				(type default)
			)
			(layer "B.SilkS")
		)
		(fp_poly
			(pts
				(xy 1.143 0.5588) (xy -1.143 0.5588) (xy -1.143 -0.5588) (xy 1.143 -0.5588)
			)
			(stroke
				(width 0)
				(type default)
			)
			(fill no)
			(layer "B.CrtYd")
		)
		(fp_line
			(start -0.508 0.3048)
			(end -0.508 -0.3048)
			(stroke
				(width 0.1)
				(type default)
			)
			(layer "B.Fab")
		)
		(fp_line
			(start 0.508 0.3048)
			(end -0.508 0.3048)
			(stroke
				(width 0.1)
				(type default)
			)
			(layer "B.Fab")
		)
		(fp_line
			(start -0.508 -0.3048)
			(end 0.508 -0.3048)
			(stroke
				(width 0.1)
				(type default)
			)
			(layer "B.Fab")
		)
		(fp_line
			(start 0.508 -0.3048)
			(end 0.508 0.3048)
			(stroke
				(width 0.1)
				(type default)
			)
			(layer "B.Fab")
		)
		(pad "1" smd rect
			(at 0.5334 0 90)
			(size 0.7112 0.6096)
			(layers "B.Cu" "B.Mask" "B.Paste")
			(net "XP3R3V_VPHY")
		)
		(pad "2" smd rect
			(at -0.5334 0 90)
			(size 0.7112 0.6096)
			(layers "B.Cu" "B.Mask" "B.Paste")
			(net "SG")
		)
		(zone
			(layer "B.Cu")
			(hatch none 0.5)
			(connect_pads
				(clearance 0)
			)
			(min_thickness 0.25)
			(keepout
				(tracks allowed)
				(vias not_allowed)
				(pads allowed)
				(copperpour not_allowed)
				(footprints allowed)
			)
			(placement
				(enabled no)
				(sheetname "")
			)
			(fill
				(thermal_gap 0.5)
				(thermal_bridge_width 0.5)
				(island_removal_mode 0)
			)
			(polygon
				(pts
					(xy 31.8262 -90.9828) (xy 32.4358 -90.9828) (xy 32.4358 -91.1352) (xy 31.8262 -91.1352)
				)
			)
		)
		(zone
			(layer "B.Cu")
			(hatch none 0.5)
			(connect_pads
				(clearance 0)
			)
			(min_thickness 0.25)
			(keepout
				(tracks not_allowed)
				(vias allowed)
				(pads allowed)
				(copperpour not_allowed)
				(footprints allowed)
			)
			(placement
				(enabled no)
				(sheetname "")
			)
			(fill
				(thermal_gap 0.5)
				(thermal_bridge_width 0.5)
				(island_removal_mode 0)
			)
			(polygon
				(pts
					(xy 31.8262 -90.9828) (xy 32.4358 -90.9828) (xy 32.4358 -91.1352) (xy 31.8262 -91.1352)
				)
			)
		)
	)
)
